
Section 2 - Conflicts on Net Synonyms
--------------------------------------

DRAWING = @S9S_MB_2U_LIB.S9S_MB_2U(SCH_1)
NET_NAME = GND
   OPF: VOLTAGE = 3.3; NET = GND
   OPF: VOLTAGE = 3.3; NET = GND
 * SCH: VOLTAGE = 0

Logical and Physical Net Conflicts 
----------------------------------

DRAWING = @S9S_MB_2U_LIB.S9S_MB_2U(SCH_1)
NET_NAME = SMB_SML1_PMBUS_3V3AUX_PCH_SCL_R0
   PNN = SMB_SML1_PMBUS_3V3AUX_PCH_SCL_R
NET_NAME = SMB_SML1_PMBUS_3V3AUX_PCH_SDA_R0
   PNN = SMB_SML1_PMBUS_3V3AUX_PCH_SDA_R
NET_NAME = SW_PVCCFA_EHV_FIVRA_CPU0_BOOT1_R
   PNN = SW_PVCCFA_EHV_FIVRA_CPU0_BOOT1_
NET_NAME = SW_PVCCFA_EHV_FIVRA_CPU0_BOOT2_R
   PNN = SW_PVCCFA_EHV_FIVRA_CPU0_BOOT2_
NET_NAME = SW_PVCCFA_EHV_FIVRA_CPU0_BOOT3_R
   PNN = SW_PVCCFA_EHV_FIVRA_CPU0_BOOT3_
NET_NAME = SW_PVCCFA_EHV_FIVRA_CPU0_BOOT4_R
   PNN = SW_PVCCFA_EHV_FIVRA_CPU0_BOOT4_
NET_NAME = SW_PVCCFA_EHV_FIVRA_CPU1_BOOT1_R
   PNN = SW_PVCCFA_EHV_FIVRA_CPU1_BOOT1_
NET_NAME = SW_PVCCFA_EHV_FIVRA_CPU1_BOOT2_R
   PNN = SW_PVCCFA_EHV_FIVRA_CPU1_BOOT2_
NET_NAME = SW_PVCCFA_EHV_FIVRA_CPU1_BOOT3_R
   PNN = SW_PVCCFA_EHV_FIVRA_CPU1_BOOT3_
NET_NAME = SW_PVCCFA_EHV_FIVRA_CPU1_BOOT4_R
   PNN = SW_PVCCFA_EHV_FIVRA_CPU1_BOOT4_
NET_NAME = P3V3_MAX11617 _VDD
   PNN = P3V3_MAX11617_VDD
NET_NAME = LED_PWRGD_PVCCFA_EHV_FIVRA_CPU0_D
   PNN = LED_PWRGD_PVCCFA_EHV_FIVRA_CP_1
NET_NAME = LED_PWRGD_PVCCFA_EHV_FIVRA_CPU1_D
   PNN = LED_PWRGD_PVCCFA_EHV_FIVRA_CP_2
NET_NAME = SMB_S3M_CPU1_PIROM_3V3AUX_SCL_R1
   PNN = SMB_S3M_CPU1_PIROM_3V3AUX_SCL_1
NET_NAME = SMB_S3M_CPU1_PIROM_3V3AUX_SDA_R1
   PNN = SMB_S3M_CPU1_PIROM_3V3AUX_SDA_1
NET_NAME = SMB_S3M_CPU0_PIROM_3V3AUX_SCL_R1
   PNN = SMB_S3M_CPU0_PIROM_3V3AUX_SCL_1
NET_NAME = SMB_S3M_CPU0_PIROM_3V3AUX_SDA_R1
   PNN = SMB_S3M_CPU0_PIROM_3V3AUX_SDA_1
NET_NAME = I3C_SPD_DDRABCD_CPU0_LVC1_SCL_R1
   PNN = I3C_SPD_DDRABCD_CPU0_LVC1_SCL_R
NET_NAME = I3C_SPD_DDRABCD_CPU0_LVC1_SCL_R2
   PNN = I3C_SPD_DDRABCD_CPU0_LVC1_SCL_1
NET_NAME = I3C_SPD_DDRABCD_CPU0_LVC1_SCL_R3
   PNN = I3C_SPD_DDRABCD_CPU0_LVC1_SCL_2
NET_NAME = I3C_SPD_DDRABCD_CPU0_LVC1_SCL_R4
   PNN = I3C_SPD_DDRABCD_CPU0_LVC1_SCL_3
NET_NAME = I3C_SPD_DDRABCD_CPU0_LVC1_SCL_R5
   PNN = I3C_SPD_DDRABCD_CPU0_LVC1_SCL_4
NET_NAME = I3C_SPD_DDRABCD_CPU0_LVC1_SCL_R6
   PNN = I3C_SPD_DDRABCD_CPU0_LVC1_SCL_5
NET_NAME = I3C_SPD_DDRABCD_CPU0_LVC1_SCL_R7
   PNN = I3C_SPD_DDRABCD_CPU0_LVC1_SCL_6
NET_NAME = I3C_SPD_DDRABCD_CPU0_LVC1_SCL_R8
   PNN = I3C_SPD_DDRABCD_CPU0_LVC1_SCL_7
NET_NAME = I3C_SPD_DDREFGH_CPU0_LVC1_SCL_R1
   PNN = I3C_SPD_DDREFGH_CPU0_LVC1_SCL_R
NET_NAME = I3C_SPD_DDREFGH_CPU0_LVC1_SCL_R2
   PNN = I3C_SPD_DDREFGH_CPU0_LVC1_SCL_1
NET_NAME = I3C_SPD_DDREFGH_CPU0_LVC1_SCL_R3
   PNN = I3C_SPD_DDREFGH_CPU0_LVC1_SCL_2
NET_NAME = I3C_SPD_DDREFGH_CPU0_LVC1_SCL_R4
   PNN = I3C_SPD_DDREFGH_CPU0_LVC1_SCL_3
NET_NAME = I3C_SPD_DDREFGH_CPU0_LVC1_SCL_R5
   PNN = I3C_SPD_DDREFGH_CPU0_LVC1_SCL_4
NET_NAME = I3C_SPD_DDREFGH_CPU0_LVC1_SCL_R6
   PNN = I3C_SPD_DDREFGH_CPU0_LVC1_SCL_5
NET_NAME = I3C_SPD_DDREFGH_CPU0_LVC1_SCL_R7
   PNN = I3C_SPD_DDREFGH_CPU0_LVC1_SCL_6
NET_NAME = I3C_SPD_DDREFGH_CPU0_LVC1_SCL_R8
   PNN = I3C_SPD_DDREFGH_CPU0_LVC1_SCL_7
NET_NAME = I3C_SPD_DDRABCD_CPU1_LVC1_SCL_R1
   PNN = I3C_SPD_DDRABCD_CPU1_LVC1_SCL_R
NET_NAME = I3C_SPD_DDRABCD_CPU1_LVC1_SCL_R2
   PNN = I3C_SPD_DDRABCD_CPU1_LVC1_SCL_1
NET_NAME = I3C_SPD_DDRABCD_CPU1_LVC1_SCL_R3
   PNN = I3C_SPD_DDRABCD_CPU1_LVC1_SCL_2
NET_NAME = I3C_SPD_DDRABCD_CPU1_LVC1_SCL_R4
   PNN = I3C_SPD_DDRABCD_CPU1_LVC1_SCL_3
NET_NAME = I3C_SPD_DDRABCD_CPU1_LVC1_SCL_R5
   PNN = I3C_SPD_DDRABCD_CPU1_LVC1_SCL_4
NET_NAME = I3C_SPD_DDRABCD_CPU1_LVC1_SCL_R6
   PNN = I3C_SPD_DDRABCD_CPU1_LVC1_SCL_5
NET_NAME = I3C_SPD_DDRABCD_CPU1_LVC1_SCL_R7
   PNN = I3C_SPD_DDRABCD_CPU1_LVC1_SCL_6
NET_NAME = I3C_SPD_DDRABCD_CPU1_LVC1_SCL_R8
   PNN = I3C_SPD_DDRABCD_CPU1_LVC1_SCL_7
NET_NAME = I3C_SPD_DDREFGH_CPU1_LVC1_SCL_R1
   PNN = I3C_SPD_DDREFGH_CPU1_LVC1_SCL_R
NET_NAME = I3C_SPD_DDREFGH_CPU1_LVC1_SCL_R2
   PNN = I3C_SPD_DDREFGH_CPU1_LVC1_SCL_1
NET_NAME = I3C_SPD_DDREFGH_CPU1_LVC1_SCL_R3
   PNN = I3C_SPD_DDREFGH_CPU1_LVC1_SCL_2
NET_NAME = I3C_SPD_DDREFGH_CPU1_LVC1_SCL_R4
   PNN = I3C_SPD_DDREFGH_CPU1_LVC1_SCL_3
NET_NAME = I3C_SPD_DDREFGH_CPU1_LVC1_SCL_R5
   PNN = I3C_SPD_DDREFGH_CPU1_LVC1_SCL_4
NET_NAME = I3C_SPD_DDREFGH_CPU1_LVC1_SCL_R6
   PNN = I3C_SPD_DDREFGH_CPU1_LVC1_SCL_5
NET_NAME = I3C_SPD_DDREFGH_CPU1_LVC1_SCL_R7
   PNN = I3C_SPD_DDREFGH_CPU1_LVC1_SCL_6
NET_NAME = I3C_SPD_DDREFGH_CPU1_LVC1_SCL_R8
   PNN = I3C_SPD_DDREFGH_CPU1_LVC1_SCL_7
NET_NAME = SMB_SML1_PMBUS_3V3AUX_PCH_SCL_R1
   PNN = SMB_SML1_PMBUS_3V3AUX_PCH_SCL_1
NET_NAME = SMB_SML1_PMBUS_3V3AUX_PCH_SDA_R1
   PNN = SMB_SML1_PMBUS_3V3AUX_PCH_SDA_1
NET_NAME = FM_PCH_XTAL_INPUT_MODE_MGPIO_TEST3
   PNN = FM_PCH_XTAL_INPUT_MODE_MGPIO_TE
NET_NAME = FM_PCH_RING_OSC_BYPASS_MGPIO_TEST2
   PNN = FM_PCH_RING_OSC_BYPASS_MGPIO_TE
NET_NAME = FM_XTAL_INPUT_FREQUENCY_1_MGPIO_TEST5
   PNN = FM_XTAL_INPUT_FREQUENCY_1_MGPIO
NET_NAME = FM_XTAL_INPUT_FREQUENCY_0_MGPIO_TEST4
   PNN = FM_XTAL_INPUT_FREQUENCY_0_MGPIO
NET_NAME = RST_PCIE_PCH_DEV_BUF_M2_0_PERST_N
   PNN = RST_PCIE_PCH_DEV_BUF_M2_0_PERST
NET_NAME = HP_LVC3_OCP_V3_2_HSC_PWRGD_PLD_R
   PNN = HP_LVC3_OCP_V3_2_HSC_PWRGD_PLD_
NET_NAME = HP_LVC3_OCP_V3_1_HSC_PWRGD_PLD_R
   PNN = HP_LVC3_OCP_V3_1_HSC_PWRGD_PLD_
NET_NAME = SMB_HOST_CLK_BUF_ISO_3V3AUX_SDA_R
   PNN = SMB_HOST_CLK_BUF_ISO_3V3AUX_S_2
NET_NAME = SMB_HOST_CLK_BUF_ISO_3V3AUX_SCL_R
   PNN = SMB_HOST_CLK_BUF_ISO_3V3AUX_S_1
